(kicad_pcb
	(version 20260206)
	(generator "pcbnew")
	(generator_version "10.0")
	(general
		(thickness 1.6)
		(legacy_teardrops no)
	)
	(paper "A4")
	(title_block
		(title "03242023_DA0F0TMBIJ0_F0T_Motherboard_J_brd_V01_OCP.brd")
		(comment 1 "Grand Teton / footprints 1712-1717 of 6105")
	)
	(layers
		(0 "F.Cu" signal "TOP")
		(4 "In1.Cu" signal "GND")
		(6 "In2.Cu" signal "IN1")
		(8 "In3.Cu" signal "GND1")
		(10 "In4.Cu" signal "IN2")
		(12 "In5.Cu" signal "GND2")
		(14 "In6.Cu" signal "IN3")
		(16 "In7.Cu" signal "GND3")
		(18 "In8.Cu" signal "VCC")
		(20 "In9.Cu" signal "VCC1")
		(22 "In10.Cu" signal "GND4")
		(24 "In11.Cu" signal "IN4")
		(26 "In12.Cu" signal "GND5")
		(28 "In13.Cu" signal "IN5")
		(30 "In14.Cu" signal "GND6")
		(32 "In15.Cu" signal "IN6")
		(34 "In16.Cu" signal "GND7")
		(2 "B.Cu" signal "BOTTOM")
		(9 "F.Adhes" user "F.Adhesive")
		(11 "B.Adhes" user "B.Adhesive")
		(13 "F.Paste" user "Package Geometry/Pastemask Top")
		(15 "B.Paste" user "Package Geometry/Pastemask Bottom")
		(5 "F.SilkS" user "Ref Des/Silkscreen Top")
		(7 "B.SilkS" user "Ref Des/Silkscreen Bottom")
		(1 "F.Mask" user "Board Geometry/Soldermask Top")
		(3 "B.Mask" user "Board Geometry/Soldermask Bottom")
		(17 "Dwgs.User" user "User.Drawings")
		(19 "Cmts.User" user "User.Comments")
		(21 "Eco1.User" user "User.Eco1")
		(23 "Eco2.User" user "User.Eco2")
		(25 "Edge.Cuts" user "Board Geometry/Outline")
		(27 "Margin" user)
		(31 "F.CrtYd" user "Package Geometry/Place Bound Top")
		(29 "B.CrtYd" user "Package Geometry/Place Bound Bottom")
		(35 "F.Fab" user "Ref Des/Assembly Top")
		(33 "B.Fab" user "Ref Des/Assembly Bottom")
	)
	(footprint ""
		(layer "F.Cu")
		(at 20.190714 -109.859826 180)
		(property "Reference" "C2052"
			(at 0 0 180)
			(layer "F.SilkS")
			(hide yes)
			(effects
				(font
					(size 1.27 1.27)
				)
			)
		)
		(property "Value" ""
			(at 0 0 180)
			(layer "F.Fab")
			(effects
				(font
					(size 1.27 1.27)
				)
			)
		)
		(duplicate_pad_numbers_are_jumpers no)
		(fp_line
			(start 0.7874 0.4064)
			(end -0.7874 0.4064)
			(stroke
				(width 0.1524)
				(type default)
			)
			(layer "F.SilkS")
		)
		(fp_line
			(start 0.7874 -0.4064)
			(end 0.7874 0.4064)
			(stroke
				(width 0.1524)
				(type default)
			)
			(layer "F.SilkS")
		)
		(fp_line
			(start -0.7874 0.4064)
			(end -0.7874 -0.4064)
			(stroke
				(width 0.1524)
				(type default)
			)
			(layer "F.SilkS")
		)
		(fp_line
			(start -0.7874 -0.4064)
			(end 0.7874 -0.4064)
			(stroke
				(width 0.1524)
				(type default)
			)
			(layer "F.SilkS")
		)
		(fp_line
			(start 0.67945 0.3048)
			(end 0.120396 0.3048)
			(stroke
				(width 0.1)
				(type default)
			)
			(layer "F.Fab")
		)
		(fp_line
			(start 0.67945 -0.3048)
			(end 0.67945 0.3048)
			(stroke
				(width 0.1)
				(type default)
			)
			(layer "F.Fab")
		)
		(fp_line
			(start 0.12065 -0.2794)
			(end 0.12065 -0.3048)
			(stroke
				(width 0.1)
				(type default)
			)
			(layer "F.Fab")
		)
		(fp_line
			(start 0.12065 -0.3048)
			(end 0.67945 -0.3048)
			(stroke
				(width 0.1)
				(type default)
			)
			(layer "F.Fab")
		)
		(fp_line
			(start 0.120396 0.3048)
			(end 0.120396 0.2794)
			(stroke
				(width 0.1)
				(type default)
			)
			(layer "F.Fab")
		)
		(fp_line
			(start 0.120396 0.2794)
			(end -0.12065 0.2794)
			(stroke
				(width 0.1)
				(type default)
			)
			(layer "F.Fab")
		)
		(fp_line
			(start -0.12065 0.3048)
			(end -0.67945 0.3048)
			(stroke
				(width 0.1)
				(type default)
			)
			(layer "F.Fab")
		)
		(fp_line
			(start -0.12065 0.2794)
			(end -0.12065 0.3048)
			(stroke
				(width 0.1)
				(type default)
			)
			(layer "F.Fab")
		)
		(fp_line
			(start -0.12065 -0.2794)
			(end 0.12065 -0.2794)
			(stroke
				(width 0.1)
				(type default)
			)
			(layer "F.Fab")
		)
		(fp_line
			(start -0.12065 -0.305054)
			(end -0.12065 -0.2794)
			(stroke
				(width 0.1)
				(type default)
			)
			(layer "F.Fab")
		)
		(fp_line
			(start -0.67945 0.3048)
			(end -0.67945 -0.305054)
			(stroke
				(width 0.1)
				(type default)
			)
			(layer "F.Fab")
		)
		(fp_line
			(start -0.67945 -0.305054)
			(end -0.12065 -0.305054)
			(stroke
				(width 0.1)
				(type default)
			)
			(layer "F.Fab")
		)
		(pad "1" smd circle
			(at -0.40005 0 180)
			(size 0 0)
			(layers "F.Cu" "F.Mask" "F.Paste")
			(net "P3V3_ADC128_VCC")
		)
		(pad "2" smd circle
			(at 0.40005 0 180)
			(size 0 0)
			(layers "F.Cu" "F.Mask" "F.Paste")
			(net "GND")
		)
	)
	(footprint ""
		(layer "F.Cu")
		(at 174.1424 -94.338648 90)
		(property "Reference" "R4598"
			(at 0 0 90)
			(layer "F.SilkS")
			(hide yes)
			(effects
				(font
					(size 1.27 1.27)
				)
			)
		)
		(property "Value" ""
			(at 0 0 90)
			(layer "F.Fab")
			(effects
				(font
					(size 1.27 1.27)
				)
			)
		)
		(duplicate_pad_numbers_are_jumpers no)
		(fp_line
			(start 0.7874 -0.4064)
			(end 0.7874 0.4064)
			(stroke
				(width 0.1524)
				(type default)
			)
			(layer "F.SilkS")
		)
		(fp_line
			(start -0.7874 -0.4064)
			(end 0.7874 -0.4064)
			(stroke
				(width 0.1524)
				(type default)
			)
			(layer "F.SilkS")
		)
		(fp_line
			(start 0.7874 0.4064)
			(end -0.7874 0.4064)
			(stroke
				(width 0.1524)
				(type default)
			)
			(layer "F.SilkS")
		)
		(fp_line
			(start -0.7874 0.4064)
			(end -0.7874 -0.4064)
			(stroke
				(width 0.1524)
				(type default)
			)
			(layer "F.SilkS")
		)
		(fp_line
			(start -0.12065 -0.305054)
			(end -0.12065 -0.2794)
			(stroke
				(width 0.1)
				(type default)
			)
			(layer "F.Fab")
		)
		(fp_line
			(start -0.67945 -0.305054)
			(end -0.12065 -0.305054)
			(stroke
				(width 0.1)
				(type default)
			)
			(layer "F.Fab")
		)
		(fp_line
			(start 0.67945 -0.3048)
			(end 0.67945 0.3048)
			(stroke
				(width 0.1)
				(type default)
			)
			(layer "F.Fab")
		)
		(fp_line
			(start 0.12065 -0.3048)
			(end 0.67945 -0.3048)
			(stroke
				(width 0.1)
				(type default)
			)
			(layer "F.Fab")
		)
		(fp_line
			(start 0.12065 -0.2794)
			(end 0.12065 -0.3048)
			(stroke
				(width 0.1)
				(type default)
			)
			(layer "F.Fab")
		)
		(fp_line
			(start -0.12065 -0.2794)
			(end 0.12065 -0.2794)
			(stroke
				(width 0.1)
				(type default)
			)
			(layer "F.Fab")
		)
		(fp_line
			(start 0.120396 0.2794)
			(end -0.12065 0.2794)
			(stroke
				(width 0.1)
				(type default)
			)
			(layer "F.Fab")
		)
		(fp_line
			(start -0.12065 0.2794)
			(end -0.12065 0.3048)
			(stroke
				(width 0.1)
				(type default)
			)
			(layer "F.Fab")
		)
		(fp_line
			(start 0.67945 0.3048)
			(end 0.120396 0.3048)
			(stroke
				(width 0.1)
				(type default)
			)
			(layer "F.Fab")
		)
		(fp_line
			(start 0.120396 0.3048)
			(end 0.120396 0.2794)
			(stroke
				(width 0.1)
				(type default)
			)
			(layer "F.Fab")
		)
		(fp_line
			(start -0.12065 0.3048)
			(end -0.67945 0.3048)
			(stroke
				(width 0.1)
				(type default)
			)
			(layer "F.Fab")
		)
		(fp_line
			(start -0.67945 0.3048)
			(end -0.67945 -0.305054)
			(stroke
				(width 0.1)
				(type default)
			)
			(layer "F.Fab")
		)
		(pad "1" smd rect
			(at -0.40005 0 270)
			(size 0.4572 0.508)
			(layers "F.Cu" "F.Mask" "F.Paste")
			(net "FM_BOARD_BMC_SKU_ID2")
		)
		(pad "2" smd rect
			(at 0.40005 0 270)
			(size 0.4572 0.508)
			(layers "F.Cu" "F.Mask" "F.Paste")
			(net "GND")
		)
	)
	(footprint ""
		(layer "F.Cu")
		(at 392.809984 -17.612614 90)
		(property "Reference" "C840"
			(at 0 0 90)
			(layer "F.SilkS")
			(hide yes)
			(effects
				(font
					(size 1.27 1.27)
				)
			)
		)
		(property "Value" ""
			(at 0 0 90)
			(layer "F.Fab")
			(effects
				(font
					(size 1.27 1.27)
				)
			)
		)
		(duplicate_pad_numbers_are_jumpers no)
		(fp_line
			(start 0.299974 -0.150114)
			(end 0.299974 0.150114)
			(stroke
				(width 0.1)
				(type default)
			)
			(layer "F.Fab")
		)
		(fp_line
			(start -0.299974 -0.150114)
			(end 0.299974 -0.150114)
			(stroke
				(width 0.1)
				(type default)
			)
			(layer "F.Fab")
		)
		(fp_line
			(start 0.299974 0.150114)
			(end -0.299974 0.150114)
			(stroke
				(width 0.1)
				(type default)
			)
			(layer "F.Fab")
		)
		(fp_line
			(start -0.299974 0.150114)
			(end -0.299974 -0.150114)
			(stroke
				(width 0.1)
				(type default)
			)
			(layer "F.Fab")
		)
		(pad "1" smd rect
			(at -0.2667 0 90)
			(size 0.3048 0.381)
			(layers "F.Cu" "F.Mask" "F.Paste")
			(net "P5E_CPU0_PE1_TX_C_DN<14>")
		)
		(pad "2" smd rect
			(at 0.2667 0 90)
			(size 0.3048 0.381)
			(layers "F.Cu" "F.Mask" "F.Paste")
			(net "P5E_CPU0_PE1_TX_DN<14>")
		)
	)
	(footprint ""
		(layer "F.Cu")
		(at 449.43014 -114.112548 -90)
		(property "Reference" "U208"
			(at -0.582168 4.89458 0)
			(unlocked yes)
			(layer "F.SilkS")
			(effects
				(font
					(size 0.7874 0.5842)
					(thickness 0.1524)
				)
				(justify left)
			)
		)
		(property "Value" ""
			(at 0 0 270)
			(layer "F.Fab")
			(effects
				(font
					(size 1.27 1.27)
				)
			)
		)
		(duplicate_pad_numbers_are_jumpers no)
		(fp_line
			(start -1.733296 1.549908)
			(end 1.733296 1.549908)
			(stroke
				(width 0.1524)
				(type default)
			)
			(layer "F.SilkS")
		)
		(fp_line
			(start 1.733296 1.549908)
			(end 1.733296 -1.549908)
			(stroke
				(width 0.1524)
				(type default)
			)
			(layer "F.SilkS")
		)
		(fp_line
			(start 0 -0.889)
			(end -0.660908 -1.549908)
			(stroke
				(width 0.1524)
				(type default)
			)
			(layer "F.SilkS")
		)
		(fp_line
			(start -1.733296 -1.549908)
			(end -1.733296 1.549908)
			(stroke
				(width 0.1524)
				(type default)
			)
			(layer "F.SilkS")
		)
		(fp_line
			(start -0.660908 -1.549908)
			(end -1.733296 -1.549908)
			(stroke
				(width 0.1524)
				(type default)
			)
			(layer "F.SilkS")
		)
		(fp_line
			(start 0.660908 -1.549908)
			(end 0 -0.889)
			(stroke
				(width 0.1524)
				(type default)
			)
			(layer "F.SilkS")
		)
		(fp_line
			(start 1.733296 -1.549908)
			(end 0.660908 -1.549908)
			(stroke
				(width 0.1524)
				(type default)
			)
			(layer "F.SilkS")
		)
		(fp_poly
			(pts
				(xy -1.9304 -0.94996) (xy -2.4384 -0.69596) (xy -2.4384 -1.20396)
			)
			(stroke
				(width 0)
				(type default)
			)
			(fill yes)
			(layer "F.SilkS")
		)
		(fp_line
			(start -0.849884 1.549908)
			(end 0.849884 1.549908)
			(stroke
				(width 0.1)
				(type default)
			)
			(layer "F.Fab")
		)
		(fp_line
			(start 0.849884 1.549908)
			(end 0.849884 -1.549908)
			(stroke
				(width 0.1)
				(type default)
			)
			(layer "F.Fab")
		)
		(fp_line
			(start -0.849884 -1.549908)
			(end -0.849884 1.549908)
			(stroke
				(width 0.1)
				(type default)
			)
			(layer "F.Fab")
		)
		(fp_line
			(start 0.849884 -1.549908)
			(end -0.849884 -1.549908)
			(stroke
				(width 0.1)
				(type default)
			)
			(layer "F.Fab")
		)
		(fp_poly
			(pts
				(xy -2.4384 -1.20396) (xy -2.4384 -0.69596) (xy -1.9304 -0.94996)
			)
			(stroke
				(width 0)
				(type default)
			)
			(fill yes)
			(layer "F.Fab")
		)
		(pad "1" smd rect
			(at -1.199896 -0.94996 180)
			(size 0.5588 0.8128)
			(layers "F.Cu" "F.Mask" "F.Paste")
			(net "HP_OCP_V3_1_EN")
		)
		(pad "2" smd rect
			(at -1.199896 0 180)
			(size 0.5588 0.8128)
			(layers "F.Cu" "F.Mask" "F.Paste")
			(net "HP_LVC3_OCP_V3_1_PRSNT2")
		)
		(pad "3" smd rect
			(at -1.199896 0.94996 180)
			(size 0.5588 0.8128)
			(layers "F.Cu" "F.Mask" "F.Paste")
			(net "GND")
		)
		(pad "4" smd rect
			(at 1.199896 0.94996 180)
			(size 0.5588 0.8128)
			(layers "F.Cu" "F.Mask" "F.Paste")
			(net "HP_LVC3_OCP_V3_1_EN")
		)
		(pad "5" smd rect
			(at 1.199896 -0.94996 180)
			(size 0.5588 0.8128)
			(layers "F.Cu" "F.Mask" "F.Paste")
			(net "P3V3_AUX")
		)
	)
	(footprint ""
		(layer "F.Cu")
		(at 355.236018 -244.03177 90)
		(property "Reference" "C1007"
			(at 0 0 90)
			(layer "F.SilkS")
			(hide yes)
			(effects
				(font
					(size 1.27 1.27)
				)
			)
		)
		(property "Value" ""
			(at 0 0 90)
			(layer "F.Fab")
			(effects
				(font
					(size 1.27 1.27)
				)
			)
		)
		(duplicate_pad_numbers_are_jumpers no)
		(fp_line
			(start 0.7874 -0.4064)
			(end 0.7874 0.4064)
			(stroke
				(width 0.1524)
				(type default)
			)
			(layer "F.SilkS")
		)
		(fp_line
			(start -0.7874 -0.4064)
			(end 0.7874 -0.4064)
			(stroke
				(width 0.1524)
				(type default)
			)
			(layer "F.SilkS")
		)
		(fp_line
			(start 0.7874 0.4064)
			(end -0.7874 0.4064)
			(stroke
				(width 0.1524)
				(type default)
			)
			(layer "F.SilkS")
		)
		(fp_line
			(start -0.7874 0.4064)
			(end -0.7874 -0.4064)
			(stroke
				(width 0.1524)
				(type default)
			)
			(layer "F.SilkS")
		)
		(fp_line
			(start -0.12065 -0.305054)
			(end -0.12065 -0.2794)
			(stroke
				(width 0.1)
				(type default)
			)
			(layer "F.Fab")
		)
		(fp_line
			(start -0.67945 -0.305054)
			(end -0.12065 -0.305054)
			(stroke
				(width 0.1)
				(type default)
			)
			(layer "F.Fab")
		)
		(fp_line
			(start 0.67945 -0.3048)
			(end 0.67945 0.3048)
			(stroke
				(width 0.1)
				(type default)
			)
			(layer "F.Fab")
		)
		(fp_line
			(start 0.12065 -0.3048)
			(end 0.67945 -0.3048)
			(stroke
				(width 0.1)
				(type default)
			)
			(layer "F.Fab")
		)
		(fp_line
			(start 0.12065 -0.2794)
			(end 0.12065 -0.3048)
			(stroke
				(width 0.1)
				(type default)
			)
			(layer "F.Fab")
		)
		(fp_line
			(start -0.12065 -0.2794)
			(end 0.12065 -0.2794)
			(stroke
				(width 0.1)
				(type default)
			)
			(layer "F.Fab")
		)
		(fp_line
			(start 0.120396 0.2794)
			(end -0.12065 0.2794)
			(stroke
				(width 0.1)
				(type default)
			)
			(layer "F.Fab")
		)
		(fp_line
			(start -0.12065 0.2794)
			(end -0.12065 0.3048)
			(stroke
				(width 0.1)
				(type default)
			)
			(layer "F.Fab")
		)
		(fp_line
			(start 0.67945 0.3048)
			(end 0.120396 0.3048)
			(stroke
				(width 0.1)
				(type default)
			)
			(layer "F.Fab")
		)
		(fp_line
			(start 0.120396 0.3048)
			(end 0.120396 0.2794)
			(stroke
				(width 0.1)
				(type default)
			)
			(layer "F.Fab")
		)
		(fp_line
			(start -0.12065 0.3048)
			(end -0.67945 0.3048)
			(stroke
				(width 0.1)
				(type default)
			)
			(layer "F.Fab")
		)
		(fp_line
			(start -0.67945 0.3048)
			(end -0.67945 -0.305054)
			(stroke
				(width 0.1)
				(type default)
			)
			(layer "F.Fab")
		)
		(pad "1" smd circle
			(at -0.40005 0 90)
			(size 0 0)
			(layers "F.Cu" "F.Mask" "F.Paste")
			(net "PVCCIN_CPU0")
		)
		(pad "2" smd circle
			(at 0.40005 0 90)
			(size 0 0)
			(layers "F.Cu" "F.Mask" "F.Paste")
			(net "GND")
		)
	)
	(footprint ""
		(layer "F.Cu")
		(at 216.1286 -121.1326)
		(property "Reference" "R4716"
			(at 0 0 0)
			(layer "F.SilkS")
			(hide yes)
			(effects
				(font
					(size 1.27 1.27)
				)
			)
		)
		(property "Value" ""
			(at 0 0 0)
			(layer "F.Fab")
			(effects
				(font
					(size 1.27 1.27)
				)
			)
		)
		(duplicate_pad_numbers_are_jumpers no)
		(fp_line
			(start -0.7874 -0.4064)
			(end 0.7874 -0.4064)
			(stroke
				(width 0.1524)
				(type default)
			)
			(layer "F.SilkS")
		)
		(fp_line
			(start -0.7874 0.4064)
			(end -0.7874 -0.4064)
			(stroke
				(width 0.1524)
				(type default)
			)
			(layer "F.SilkS")
		)
		(fp_line
			(start 0.7874 -0.4064)
			(end 0.7874 0.4064)
			(stroke
				(width 0.1524)
				(type default)
			)
			(layer "F.SilkS")
		)
		(fp_line
			(start 0.7874 0.4064)
			(end -0.7874 0.4064)
			(stroke
				(width 0.1524)
				(type default)
			)
			(layer "F.SilkS")
		)
		(fp_line
			(start -0.67945 -0.305054)
			(end -0.12065 -0.305054)
			(stroke
				(width 0.1)
				(type default)
			)
			(layer "F.Fab")
		)
		(fp_line
			(start -0.67945 0.3048)
			(end -0.67945 -0.305054)
			(stroke
				(width 0.1)
				(type default)
			)
			(layer "F.Fab")
		)
		(fp_line
			(start -0.12065 -0.305054)
			(end -0.12065 -0.2794)
			(stroke
				(width 0.1)
				(type default)
			)
			(layer "F.Fab")
		)
		(fp_line
			(start -0.12065 -0.2794)
			(end 0.12065 -0.2794)
			(stroke
				(width 0.1)
				(type default)
			)
			(layer "F.Fab")
		)
		(fp_line
			(start -0.12065 0.2794)
			(end -0.12065 0.3048)
			(stroke
				(width 0.1)
				(type default)
			)
			(layer "F.Fab")
		)
		(fp_line
			(start -0.12065 0.3048)
			(end -0.67945 0.3048)
			(stroke
				(width 0.1)
				(type default)
			)
			(layer "F.Fab")
		)
		(fp_line
			(start 0.120396 0.2794)
			(end -0.12065 0.2794)
			(stroke
				(width 0.1)
				(type default)
			)
			(layer "F.Fab")
		)
		(fp_line
			(start 0.120396 0.3048)
			(end 0.120396 0.2794)
			(stroke
				(width 0.1)
				(type default)
			)
			(layer "F.Fab")
		)
		(fp_line
			(start 0.12065 -0.3048)
			(end 0.67945 -0.3048)
			(stroke
				(width 0.1)
				(type default)
			)
			(layer "F.Fab")
		)
		(fp_line
			(start 0.12065 -0.2794)
			(end 0.12065 -0.3048)
			(stroke
				(width 0.1)
				(type default)
			)
			(layer "F.Fab")
		)
		(fp_line
			(start 0.67945 -0.3048)
			(end 0.67945 0.3048)
			(stroke
				(width 0.1)
				(type default)
			)
			(layer "F.Fab")
		)
		(fp_line
			(start 0.67945 0.3048)
			(end 0.120396 0.3048)
			(stroke
				(width 0.1)
				(type default)
			)
			(layer "F.Fab")
		)
		(pad "1" smd circle
			(at -0.40005 0)
			(size 0 0)
			(layers "F.Cu" "F.Mask" "F.Paste")
			(net "P3V3_AUX")
		)
		(pad "2" smd circle
			(at 0.40005 0)
			(size 0 0)
			(layers "F.Cu" "F.Mask" "F.Paste")
			(net "FM_AC_PWR_BTN_R_N")
		)
	)
)
